(kicad_pcb
	(version 20241229)
	(generator "pcbnew")
	(generator_version "9.0")
	(general
		(thickness 1.63)
		(legacy_teardrops no)
	)
	(paper "A4")
	(title_block
		(title "CM4 Baseboard")
		(date "2026-01-05")
		(rev "1.1.1")
		(company "Antmicro Ltd")
		(comment 1 "www.antmicro.com")
		(comment 9 "footprints 370-371 of 506")
	)
	(layers
		(0 "F.Cu" signal)
		(4 "In1.Cu" power)
		(6 "In2.Cu" power)
		(8 "In3.Cu" signal)
		(10 "In4.Cu" signal)
		(2 "B.Cu" signal)
		(9 "F.Adhes" user "F.Adhesive")
		(11 "B.Adhes" user "B.Adhesive")
		(13 "F.Paste" user)
		(15 "B.Paste" user)
		(5 "F.SilkS" user "F.Silkscreen")
		(7 "B.SilkS" user "B.Silkscreen")
		(1 "F.Mask" user)
		(3 "B.Mask" user)
		(17 "Dwgs.User" user "User.Drawings")
		(19 "Cmts.User" user "User.Comments")
		(21 "Eco1.User" user "User.Eco1")
		(23 "Eco2.User" user "User.Eco2")
		(25 "Edge.Cuts" user)
		(27 "Margin" user)
		(31 "F.CrtYd" user "F.Courtyard")
		(29 "B.CrtYd" user "B.Courtyard")
		(35 "F.Fab" user)
		(33 "B.Fab" user)
	)
	(footprint "antmicro-footprints:Spacer_Drill3.7mm_H6mm_9774060151R"
		(layer "B.Cu")
		(at 41.917962 174.7165)
		(descr "Spacer M=3 h=36mm fi=5.1mm")
		(property "Reference" "H104"
			(at 1.34 4.02 180)
			(layer "B.SilkS")
			(effects
				(font
					(size 0.7 0.7)
					(thickness 0.15)
				)
				(justify left bottom mirror)
			)
		)
		(property "Value" "Spacer_Drill3.7mm_H6mm_9774060151R"
			(at 0 -4 180)
			(layer "B.Fab")
			(effects
				(font
					(size 0.7 0.7)
					(thickness 0.15)
				)
				(justify left bottom mirror)
			)
		)
		(property "Datasheet" "https://www.we-online.com/components/products/datasheet/9774060151R.pdf"
			(at 0 0 0)
			(layer "B.Fab")
			(hide yes)
			(effects
				(font
					(size 1.27 1.27)
					(thickness 0.15)
				)
			)
		)
		(property "Manufacturer" "Würth Elektronik"
			(at 0 0 0)
			(unlocked yes)
			(layer "B.Fab")
			(hide yes)
			(effects
				(font
					(size 1 1)
					(thickness 0.15)
				)
				(justify mirror)
			)
		)
		(property "MPN" "9774060151R"
			(at 0 0 0)
			(unlocked yes)
			(layer "B.Fab")
			(hide yes)
			(effects
				(font
					(size 1 1)
					(thickness 0.15)
				)
				(justify mirror)
			)
		)
		(property "Author" "Antmicro"
			(at 0 0 0)
			(unlocked yes)
			(layer "B.Fab")
			(hide yes)
			(effects
				(font
					(size 1 1)
					(thickness 0.15)
				)
				(justify mirror)
			)
		)
		(property "License" "Apache-2.0"
			(at 0 0 0)
			(unlocked yes)
			(layer "B.Fab")
			(hide yes)
			(effects
				(font
					(size 1 1)
					(thickness 0.15)
				)
				(justify mirror)
			)
		)
		(sheetname "/")
		(sheetfile "cm4-baseboard.kicad_sch")
		(solder_paste_margin_ratio -1)
		(attr smd)
		(fp_circle
			(center 0 0)
			(end 3.05 0)
			(stroke
				(width 0.05)
				(type solid)
			)
			(fill no)
			(layer "B.CrtYd")
		)
		(fp_circle
			(center 0 0)
			(end 2.6 0)
			(stroke
				(width 0.15)
				(type solid)
			)
			(fill no)
			(layer "B.Fab")
		)
		(fp_text user "${REFERENCE}"
			(at -9.6 -6.5 180)
			(layer "B.Fab")
			(effects
				(font
					(size 0.7 0.7)
					(thickness 0.15)
				)
				(justify left bottom mirror)
			)
		)
		(fp_text user "License: Apache-2.0"
			(at -9.6 -8.9 180)
			(layer "B.Fab")
			(effects
				(font
					(size 0.7 0.7)
					(thickness 0.15)
				)
				(justify left bottom mirror)
			)
		)
		(fp_text user "Author: Antmicro"
			(at -9.6 -7.7 180)
			(layer "B.Fab")
			(effects
				(font
					(size 0.7 0.7)
					(thickness 0.15)
				)
				(justify left bottom mirror)
			)
		)
		(pad "" smd custom
			(at -1.7 -1.7 270)
			(size 0.62 0.62)
			(layers "B.Paste")
			(thermal_bridge_angle 90)
			(options
				(clearance outline)
				(anchor circle)
			)
			(primitives
				(gr_arc
					(start 1.266786 0.24747)
					(mid 0.285453 -0.29439)
					(end -0.250195 -1.279127)
					(width 0.2)
				)
				(gr_arc
					(start 1.259603 0.339191)
					(mid 0.218448 -0.232561)
					(end -0.34334 -1.279127)
					(width 0.2)
				)
				(gr_arc
					(start 1.255279 0.431435)
					(mid 0.152481 -0.169693)
					(end -0.436309 -1.279127)
					(width 0.2)
				)
				(gr_arc
					(start 1.253811 0.524161)
					(mid 0.087542 -0.105784)
					(end -0.529126 -1.279127)
					(width 0.2)
				)
				(gr_arc
					(start 1.275473 0.621136)
					(mid 0.0309 -0.033527)
					(end -0.621807 -1.279127)
					(width 0.2)
				)
				(gr_arc
					(start 1.263664 0.711602)
					(mid -0.037759 0.026651)
					(end -0.71437 -1.279127)
					(width 0.2)
				)
				(gr_arc
					(start 1.253435 0.802342)
					(mid -0.105837 0.087395)
					(end -0.806826 -1.279127)
					(width 0.2)
				)
				(gr_arc
					(start 1.267475 0.897258)
					(mid -0.165236 0.156885)
					(end -0.899187 -1.279127)
					(width 0.2)
				)
				(gr_arc
					(start 1.270645 0.990112)
					(mid -0.228522 0.222449)
					(end -0.991463 -1.279127)
					(width 0.2)
				)
				(gr_arc
					(start 1.266278 1.081674)
					(mid -0.294507 0.285313)
					(end -1.083663 -1.279127)
					(width 0.2)
				)
				(gr_line
					(start 1.279127 0.250195)
					(end 1.279127 1.083663)
					(width 0.2)
				)
				(gr_line
					(start -0.250195 -1.279127)
					(end -1.083663 -1.279127)
					(width 0.2)
				)
			)
		)
		(pad "" smd custom
			(at -1.7 1.7)
			(size 0.62 0.62)
			(layers "B.Paste")
			(thermal_bridge_angle 90)
			(options
				(clearance outline)
				(anchor circle)
			)
			(primitives
				(gr_arc
					(start 1.266786 0.24747)
					(mid 0.285453 -0.29439)
					(end -0.250195 -1.279127)
					(width 0.2)
				)
				(gr_arc
					(start 1.259603 0.339191)
					(mid 0.218448 -0.232561)
					(end -0.34334 -1.279127)
					(width 0.2)
				)
				(gr_arc
					(start 1.255279 0.431435)
					(mid 0.152481 -0.169693)
					(end -0.436309 -1.279127)
					(width 0.2)
				)
				(gr_arc
					(start 1.253811 0.524161)
					(mid 0.087542 -0.105784)
					(end -0.529126 -1.279127)
					(width 0.2)
				)
				(gr_arc
					(start 1.275473 0.621136)
					(mid 0.0309 -0.033527)
					(end -0.621807 -1.279127)
					(width 0.2)
				)
				(gr_arc
					(start 1.263664 0.711602)
					(mid -0.037759 0.026651)
					(end -0.71437 -1.279127)
					(width 0.2)
				)
				(gr_arc
					(start 1.253435 0.802342)
					(mid -0.105837 0.087395)
					(end -0.806826 -1.279127)
					(width 0.2)
				)
				(gr_arc
					(start 1.267475 0.897258)
					(mid -0.165236 0.156885)
					(end -0.899187 -1.279127)
					(width 0.2)
				)
				(gr_arc
					(start 1.270645 0.990112)
					(mid -0.228522 0.222449)
					(end -0.991463 -1.279127)
					(width 0.2)
				)
				(gr_arc
					(start 1.266278 1.081674)
					(mid -0.294507 0.285313)
					(end -1.083663 -1.279127)
					(width 0.2)
				)
				(gr_line
					(start 1.279127 0.250195)
					(end 1.279127 1.083663)
					(width 0.2)
				)
				(gr_line
					(start -0.250195 -1.279127)
					(end -1.083663 -1.279127)
					(width 0.2)
				)
			)
		)
		(pad "" smd custom
			(at 1.7 -1.7 180)
			(size 0.62 0.62)
			(layers "B.Paste")
			(thermal_bridge_angle 90)
			(options
				(clearance outline)
				(anchor circle)
			)
			(primitives
				(gr_arc
					(start 1.266786 0.24747)
					(mid 0.285453 -0.29439)
					(end -0.250195 -1.279127)
					(width 0.2)
				)
				(gr_arc
					(start 1.259603 0.339191)
					(mid 0.218448 -0.232561)
					(end -0.34334 -1.279127)
					(width 0.2)
				)
				(gr_arc
					(start 1.255279 0.431435)
					(mid 0.152481 -0.169693)
					(end -0.436309 -1.279127)
					(width 0.2)
				)
				(gr_arc
					(start 1.253811 0.524161)
					(mid 0.087542 -0.105784)
					(end -0.529126 -1.279127)
					(width 0.2)
				)
				(gr_arc
					(start 1.275473 0.621136)
					(mid 0.0309 -0.033527)
					(end -0.621807 -1.279127)
					(width 0.2)
				)
				(gr_arc
					(start 1.263664 0.711602)
					(mid -0.037759 0.026651)
					(end -0.71437 -1.279127)
					(width 0.2)
				)
				(gr_arc
					(start 1.253435 0.802342)
					(mid -0.105837 0.087395)
					(end -0.806826 -1.279127)
					(width 0.2)
				)
				(gr_arc
					(start 1.267475 0.897258)
					(mid -0.165236 0.156885)
					(end -0.899187 -1.279127)
					(width 0.2)
				)
				(gr_arc
					(start 1.270645 0.990112)
					(mid -0.228522 0.222449)
					(end -0.991463 -1.279127)
					(width 0.2)
				)
				(gr_arc
					(start 1.266278 1.081674)
					(mid -0.294507 0.285313)
					(end -1.083663 -1.279127)
					(width 0.2)
				)
				(gr_line
					(start 1.279127 0.250195)
					(end 1.279127 1.083663)
					(width 0.2)
				)
				(gr_line
					(start -0.250195 -1.279127)
					(end -1.083663 -1.279127)
					(width 0.2)
				)
			)
		)
		(pad "" smd custom
			(at 1.7 1.7 90)
			(size 0.62 0.62)
			(layers "B.Paste")
			(thermal_bridge_angle 90)
			(options
				(clearance outline)
				(anchor circle)
			)
			(primitives
				(gr_arc
					(start 1.266786 0.24747)
					(mid 0.285453 -0.29439)
					(end -0.250195 -1.279127)
					(width 0.2)
				)
				(gr_arc
					(start 1.259603 0.339191)
					(mid 0.218448 -0.232561)
					(end -0.34334 -1.279127)
					(width 0.2)
				)
				(gr_arc
					(start 1.255279 0.431435)
					(mid 0.152481 -0.169693)
					(end -0.436309 -1.279127)
					(width 0.2)
				)
				(gr_arc
					(start 1.253811 0.524161)
					(mid 0.087542 -0.105784)
					(end -0.529126 -1.279127)
					(width 0.2)
				)
				(gr_arc
					(start 1.275473 0.621136)
					(mid 0.0309 -0.033527)
					(end -0.621807 -1.279127)
					(width 0.2)
				)
				(gr_arc
					(start 1.263664 0.711602)
					(mid -0.037759 0.026651)
					(end -0.71437 -1.279127)
					(width 0.2)
				)
				(gr_arc
					(start 1.253435 0.802342)
					(mid -0.105837 0.087395)
					(end -0.806826 -1.279127)
					(width 0.2)
				)
				(gr_arc
					(start 1.267475 0.897258)
					(mid -0.165236 0.156885)
					(end -0.899187 -1.279127)
					(width 0.2)
				)
				(gr_arc
					(start 1.270645 0.990112)
					(mid -0.228522 0.222449)
					(end -0.991463 -1.279127)
					(width 0.2)
				)
				(gr_arc
					(start 1.266278 1.081674)
					(mid -0.294507 0.285313)
					(end -1.083663 -1.279127)
					(width 0.2)
				)
				(gr_line
					(start 1.279127 0.250195)
					(end 1.279127 1.083663)
					(width 0.2)
				)
				(gr_line
					(start -0.250195 -1.279127)
					(end -1.083663 -1.279127)
					(width 0.2)
				)
			)
		)
		(pad "1" thru_hole circle
			(at 0 0)
			(size 6 6)
			(drill 3.7)
			(layers "*.Cu" "*.Mask")
			(remove_unused_layers no)
			(net 3 "GND")
			(pintype "passive")
		)
	)
	(footprint "antmicro-footprints:Spacer_Drill3.7mm_H6mm_9774060151R"
		(layer "B.Cu")
		(at 138.917962 116.7165 180)
		(descr "Spacer M=3 h=36mm fi=5.1mm")
		(property "Reference" "H101"
			(at 0 3.2 0)
			(layer "B.SilkS")
			(effects
				(font
					(size 0.7 0.7)
					(thickness 0.15)
				)
				(justify left bottom mirror)
			)
		)
		(property "Value" "Spacer_Drill3.7mm_H6mm_9774060151R"
			(at 0 -4 0)
			(layer "B.Fab")
			(effects
				(font
					(size 0.7 0.7)
					(thickness 0.15)
				)
				(justify left bottom mirror)
			)
		)
		(property "Datasheet" "https://www.we-online.com/components/products/datasheet/9774060151R.pdf"
			(at 0 0 180)
			(layer "B.Fab")
			(hide yes)
			(effects
				(font
					(size 1.27 1.27)
					(thickness 0.15)
				)
			)
		)
		(property "Manufacturer" "Würth Elektronik"
			(at 0 0 180)
			(unlocked yes)
			(layer "B.Fab")
			(hide yes)
			(effects
				(font
					(size 1 1)
					(thickness 0.15)
				)
				(justify mirror)
			)
		)
		(property "MPN" "9774060151R"
			(at 0 0 180)
			(unlocked yes)
			(layer "B.Fab")
			(hide yes)
			(effects
				(font
					(size 1 1)
					(thickness 0.15)
				)
				(justify mirror)
			)
		)
		(property "Author" "Antmicro"
			(at 0 0 180)
			(unlocked yes)
			(layer "B.Fab")
			(hide yes)
			(effects
				(font
					(size 1 1)
					(thickness 0.15)
				)
				(justify mirror)
			)
		)
		(property "License" "Apache-2.0"
			(at 0 0 180)
			(unlocked yes)
			(layer "B.Fab")
			(hide yes)
			(effects
				(font
					(size 1 1)
					(thickness 0.15)
				)
				(justify mirror)
			)
		)
		(sheetname "/")
		(sheetfile "cm4-baseboard.kicad_sch")
		(solder_paste_margin_ratio -1)
		(attr smd)
		(fp_circle
			(center 0 0)
			(end 3.05 0)
			(stroke
				(width 0.05)
				(type solid)
			)
			(fill no)
			(layer "B.CrtYd")
		)
		(fp_circle
			(center 0 0)
			(end 2.6 0)
			(stroke
				(width 0.15)
				(type solid)
			)
			(fill no)
			(layer "B.Fab")
		)
		(fp_text user "Author: Antmicro"
			(at -9.6 -7.7 0)
			(layer "B.Fab")
			(effects
				(font
					(size 0.7 0.7)
					(thickness 0.15)
				)
				(justify left bottom mirror)
			)
		)
		(fp_text user "License: Apache-2.0"
			(at -9.6 -8.9 0)
			(layer "B.Fab")
			(effects
				(font
					(size 0.7 0.7)
					(thickness 0.15)
				)
				(justify left bottom mirror)
			)
		)
		(fp_text user "${REFERENCE}"
			(at -9.6 -6.5 0)
			(layer "B.Fab")
			(effects
				(font
					(size 0.7 0.7)
					(thickness 0.15)
				)
				(justify left bottom mirror)
			)
		)
		(pad "" smd custom
			(at -1.7 -1.7 90)
			(size 0.62 0.62)
			(layers "B.Paste")
			(thermal_bridge_angle 90)
			(options
				(clearance outline)
				(anchor circle)
			)
			(primitives
				(gr_arc
					(start 1.266786 0.24747)
					(mid 0.285453 -0.29439)
					(end -0.250195 -1.279127)
					(width 0.2)
				)
				(gr_arc
					(start 1.259603 0.339191)
					(mid 0.218448 -0.232561)
					(end -0.34334 -1.279127)
					(width 0.2)
				)
				(gr_arc
					(start 1.255279 0.431435)
					(mid 0.152481 -0.169693)
					(end -0.436309 -1.279127)
					(width 0.2)
				)
				(gr_arc
					(start 1.253811 0.524161)
					(mid 0.087542 -0.105784)
					(end -0.529126 -1.279127)
					(width 0.2)
				)
				(gr_arc
					(start 1.275473 0.621136)
					(mid 0.0309 -0.033527)
					(end -0.621807 -1.279127)
					(width 0.2)
				)
				(gr_arc
					(start 1.263664 0.711602)
					(mid -0.037759 0.026651)
					(end -0.71437 -1.279127)
					(width 0.2)
				)
				(gr_arc
					(start 1.253435 0.802342)
					(mid -0.105837 0.087395)
					(end -0.806826 -1.279127)
					(width 0.2)
				)
				(gr_arc
					(start 1.267475 0.897258)
					(mid -0.165236 0.156885)
					(end -0.899187 -1.279127)
					(width 0.2)
				)
				(gr_arc
					(start 1.270645 0.990112)
					(mid -0.228522 0.222449)
					(end -0.991463 -1.279127)
					(width 0.2)
				)
				(gr_arc
					(start 1.266278 1.081674)
					(mid -0.294507 0.285313)
					(end -1.083663 -1.279127)
					(width 0.2)
				)
				(gr_line
					(start 1.279127 0.250195)
					(end 1.279127 1.083663)
					(width 0.2)
				)
				(gr_line
					(start -0.250195 -1.279127)
					(end -1.083663 -1.279127)
					(width 0.2)
				)
			)
		)
		(pad "" smd custom
			(at -1.7 1.7 180)
			(size 0.62 0.62)
			(layers "B.Paste")
			(thermal_bridge_angle 90)
			(options
				(clearance outline)
				(anchor circle)
			)
			(primitives
				(gr_arc
					(start 1.266786 0.24747)
					(mid 0.285453 -0.29439)
					(end -0.250195 -1.279127)
					(width 0.2)
				)
				(gr_arc
					(start 1.259603 0.339191)
					(mid 0.218448 -0.232561)
					(end -0.34334 -1.279127)
					(width 0.2)
				)
				(gr_arc
					(start 1.255279 0.431435)
					(mid 0.152481 -0.169693)
					(end -0.436309 -1.279127)
					(width 0.2)
				)
				(gr_arc
					(start 1.253811 0.524161)
					(mid 0.087542 -0.105784)
					(end -0.529126 -1.279127)
					(width 0.2)
				)
				(gr_arc
					(start 1.275473 0.621136)
					(mid 0.0309 -0.033527)
					(end -0.621807 -1.279127)
					(width 0.2)
				)
				(gr_arc
					(start 1.263664 0.711602)
					(mid -0.037759 0.026651)
					(end -0.71437 -1.279127)
					(width 0.2)
				)
				(gr_arc
					(start 1.253435 0.802342)
					(mid -0.105837 0.087395)
					(end -0.806826 -1.279127)
					(width 0.2)
				)
				(gr_arc
					(start 1.267475 0.897258)
					(mid -0.165236 0.156885)
					(end -0.899187 -1.279127)
					(width 0.2)
				)
				(gr_arc
					(start 1.270645 0.990112)
					(mid -0.228522 0.222449)
					(end -0.991463 -1.279127)
					(width 0.2)
				)
				(gr_arc
					(start 1.266278 1.081674)
					(mid -0.294507 0.285313)
					(end -1.083663 -1.279127)
					(width 0.2)
				)
				(gr_line
					(start 1.279127 0.250195)
					(end 1.279127 1.083663)
					(width 0.2)
				)
				(gr_line
					(start -0.250195 -1.279127)
					(end -1.083663 -1.279127)
					(width 0.2)
				)
			)
		)
		(pad "" smd custom
			(at 1.7 -1.7)
			(size 0.62 0.62)
			(layers "B.Paste")
			(thermal_bridge_angle 90)
			(options
				(clearance outline)
				(anchor circle)
			)
			(primitives
				(gr_arc
					(start 1.266786 0.24747)
					(mid 0.285453 -0.29439)
					(end -0.250195 -1.279127)
					(width 0.2)
				)
				(gr_arc
					(start 1.259603 0.339191)
					(mid 0.218448 -0.232561)
					(end -0.34334 -1.279127)
					(width 0.2)
				)
				(gr_arc
					(start 1.255279 0.431435)
					(mid 0.152481 -0.169693)
					(end -0.436309 -1.279127)
					(width 0.2)
				)
				(gr_arc
					(start 1.253811 0.524161)
					(mid 0.087542 -0.105784)
					(end -0.529126 -1.279127)
					(width 0.2)
				)
				(gr_arc
					(start 1.275473 0.621136)
					(mid 0.0309 -0.033527)
					(end -0.621807 -1.279127)
					(width 0.2)
				)
				(gr_arc
					(start 1.263664 0.711602)
					(mid -0.037759 0.026651)
					(end -0.71437 -1.279127)
					(width 0.2)
				)
				(gr_arc
					(start 1.253435 0.802342)
					(mid -0.105837 0.087395)
					(end -0.806826 -1.279127)
					(width 0.2)
				)
				(gr_arc
					(start 1.267475 0.897258)
					(mid -0.165236 0.156885)
					(end -0.899187 -1.279127)
					(width 0.2)
				)
				(gr_arc
					(start 1.270645 0.990112)
					(mid -0.228522 0.222449)
					(end -0.991463 -1.279127)
					(width 0.2)
				)
				(gr_arc
					(start 1.266278 1.081674)
					(mid -0.294507 0.285313)
					(end -1.083663 -1.279127)
					(width 0.2)
				)
				(gr_line
					(start 1.279127 0.250195)
					(end 1.279127 1.083663)
					(width 0.2)
				)
				(gr_line
					(start -0.250195 -1.279127)
					(end -1.083663 -1.279127)
					(width 0.2)
				)
			)
		)
		(pad "" smd custom
			(at 1.7 1.7 270)
			(size 0.62 0.62)
			(layers "B.Paste")
			(thermal_bridge_angle 90)
			(options
				(clearance outline)
				(anchor circle)
			)
			(primitives
				(gr_arc
					(start 1.266786 0.24747)
					(mid 0.285453 -0.29439)
					(end -0.250195 -1.279127)
					(width 0.2)
				)
				(gr_arc
					(start 1.259603 0.339191)
					(mid 0.218448 -0.232561)
					(end -0.34334 -1.279127)
					(width 0.2)
				)
				(gr_arc
					(start 1.255279 0.431435)
					(mid 0.152481 -0.169693)
					(end -0.436309 -1.279127)
					(width 0.2)
				)
				(gr_arc
					(start 1.253811 0.524161)
					(mid 0.087542 -0.105784)
					(end -0.529126 -1.279127)
					(width 0.2)
				)
				(gr_arc
					(start 1.275473 0.621136)
					(mid 0.0309 -0.033527)
					(end -0.621807 -1.279127)
					(width 0.2)
				)
				(gr_arc
					(start 1.263664 0.711602)
					(mid -0.037759 0.026651)
					(end -0.71437 -1.279127)
					(width 0.2)
				)
				(gr_arc
					(start 1.253435 0.802342)
					(mid -0.105837 0.087395)
					(end -0.806826 -1.279127)
					(width 0.2)
				)
				(gr_arc
					(start 1.267475 0.897258)
					(mid -0.165236 0.156885)
					(end -0.899187 -1.279127)
					(width 0.2)
				)
				(gr_arc
					(start 1.270645 0.990112)
					(mid -0.228522 0.222449)
					(end -0.991463 -1.279127)
					(width 0.2)
				)
				(gr_arc
					(start 1.266278 1.081674)
					(mid -0.294507 0.285313)
					(end -1.083663 -1.279127)
					(width 0.2)
				)
				(gr_line
					(start 1.279127 0.250195)
					(end 1.279127 1.083663)
					(width 0.2)
				)
				(gr_line
					(start -0.250195 -1.279127)
					(end -1.083663 -1.279127)
					(width 0.2)
				)
			)
		)
		(pad "1" thru_hole circle
			(at 0 0 180)
			(size 6 6)
			(drill 3.7)
			(layers "*.Cu" "*.Mask")
			(remove_unused_layers no)
			(net 3 "GND")
			(pintype "passive")
		)
	)
)
